# BASEBOARD_FAB2 (Tioga Pass) — schematic netlist excerpt (pin names and nets, part order shuffled) for the footprints in the layout excerpt that follows; sources: Cadence DE-HDL packaged netlist, KiCad conversion of Wiwynn_Tioga_Pass_MB.brd

C5P33  CAP  47UF 4V 20% X6S  pkg 0805  page 42 : A = PVCCIN_CPU0 ; B = GND
R2U18  RES  0.0 5% CHIP  pkg 0402  page 107 : A = P3E_CPU0_PE1_SS_RXP<2> ; B = P3E_CPU0_PE1_SS_R_RXP<2>
C9U4  CAP  10UF 16V 10% X6S  pkg 0805  page 224 : A = VR_FET_SW_P12V_STBY_PVDDQ_GHJ ; B = GND

(kicad_pcb
	(version 20260206)
	(generator "pcbnew")
	(generator_version "10.0")
	(general
		(thickness 1.6)
		(legacy_teardrops no)
	)
	(paper "A4")
	(title_block
		(title "Wiwynn_Tioga_Pass_MB.brd")
		(comment 1 "Tioga Pass / footprints 4550-4552 of 4770")
	)
	(layers
		(0 "F.Cu" signal "TOP")
		(4 "In1.Cu" signal "L2GND")
		(6 "In2.Cu" signal "L3")
		(8 "In3.Cu" signal "L4GND")
		(10 "In4.Cu" signal "L5")
		(12 "In5.Cu" signal "L6GND")
		(14 "In6.Cu" signal "L7VCC")
		(16 "In7.Cu" signal "L8VCC")
		(18 "In8.Cu" signal "L9GND")
		(20 "In9.Cu" signal "L10")
		(22 "In10.Cu" signal "L11GND")
		(24 "In11.Cu" signal "L12")
		(26 "In12.Cu" signal "L13GND")
		(2 "B.Cu" signal "BOTTOM")
		(9 "F.Adhes" user "F.Adhesive")
		(11 "B.Adhes" user "B.Adhesive")
		(13 "F.Paste" user "Package Geometry/Pastemask Top")
		(15 "B.Paste" user "Package Geometry/Pastemask Bottom")
		(5 "F.SilkS" user "Ref Des/Silkscreen Top")
		(7 "B.SilkS" user "Ref Des/Silkscreen Bottom")
		(1 "F.Mask" user "Board Geometry/Soldermask Top")
		(3 "B.Mask" user "Board Geometry/Soldermask Bottom")
		(17 "Dwgs.User" user "User.Drawings")
		(19 "Cmts.User" user "User.Comments")
		(21 "Eco1.User" user "User.Eco1")
		(23 "Eco2.User" user "User.Eco2")
		(25 "Edge.Cuts" user "Board Geometry/Outline")
		(27 "Margin" user)
		(31 "F.CrtYd" user "Package Geometry/Place Bound Top")
		(29 "B.CrtYd" user "Package Geometry/Place Bound Bottom")
		(35 "F.Fab" user "Ref Des/Assembly Top")
		(33 "B.Fab" user "Ref Des/Assembly Bottom")
	)
	(footprint ""
		(layer "B.Cu")
		(at 265.864086 -73.51014)
		(property "Reference" "C5P33"
			(at 0 0 0)
			(layer "B.SilkS")
			(hide yes)
			(effects
				(font
					(size 1.27 1.27)
				)
				(justify mirror)
			)
		)
		(property "Value" ""
			(at 0 0 0)
			(layer "B.Fab")
			(effects
				(font
					(size 1.27 1.27)
				)
				(justify mirror)
			)
		)
		(duplicate_pad_numbers_are_jumpers no)
		(fp_poly
			(pts
				(xy 0.7239 -0.2159) (xy -0.7239 -0.2159) (xy -0.7239 1.9939) (xy 0.7239 1.9939)
			)
			(stroke
				(width 0)
				(type default)
			)
			(fill no)
			(layer "B.CrtYd")
		)
		(fp_line
			(start -0.7239 -0.2159)
			(end 0.7239 -0.2159)
			(stroke
				(width 0.1)
				(type default)
			)
			(layer "B.Fab")
		)
		(fp_line
			(start -0.7239 1.9939)
			(end -0.7239 -0.2159)
			(stroke
				(width 0.1)
				(type default)
			)
			(layer "B.Fab")
		)
		(fp_line
			(start 0.7239 -0.2159)
			(end 0.7239 1.9939)
			(stroke
				(width 0.1)
				(type default)
			)
			(layer "B.Fab")
		)
		(fp_line
			(start 0.7239 1.9939)
			(end -0.7239 1.9939)
			(stroke
				(width 0.1)
				(type default)
			)
			(layer "B.Fab")
		)
		(pad "1" smd rect
			(at 0 0 180)
			(size 1.27 1.016)
			(layers "B.Cu" "B.Mask" "B.Paste")
			(net "PVCCIN_CPU0")
		)
		(pad "2" smd rect
			(at 0 1.778 180)
			(size 1.27 1.016)
			(layers "B.Cu" "B.Mask" "B.Paste")
			(net "GND")
		)
		(zone
			(layer "B.Cu")
			(hatch none 0.5)
			(connect_pads
				(clearance 0)
			)
			(min_thickness 0.25)
			(keepout
				(tracks not_allowed)
				(vias allowed)
				(pads allowed)
				(copperpour not_allowed)
				(footprints allowed)
			)
			(placement
				(enabled no)
				(sheetname "")
			)
			(fill
				(thermal_gap 0.5)
				(thermal_bridge_width 0.5)
				(island_removal_mode 0)
			)
			(polygon
				(pts
					(xy 266.499086 -73.00214) (xy 265.229086 -73.00214) (xy 265.229086 -72.24014) (xy 266.499086 -72.24014)
				)
			)
		)
	)
	(footprint ""
		(layer "B.Cu")
		(at 3.8227 -9.564116 90)
		(property "Reference" "C9U4"
			(at 0 0 90)
			(layer "B.SilkS")
			(hide yes)
			(effects
				(font
					(size 1.27 1.27)
				)
				(justify mirror)
			)
		)
		(property "Value" ""
			(at 0 0 90)
			(layer "B.Fab")
			(effects
				(font
					(size 1.27 1.27)
				)
				(justify mirror)
			)
		)
		(duplicate_pad_numbers_are_jumpers no)
		(fp_rect
			(start -0.7239 -0.2159)
			(end 0.7239 1.9939)
			(stroke
				(width 0)
				(type default)
			)
			(fill no)
			(layer "B.CrtYd")
		)
		(fp_line
			(start 0.7239 -0.2159)
			(end 0.7239 1.9939)
			(stroke
				(width 0.1)
				(type default)
			)
			(layer "B.Fab")
		)
		(fp_line
			(start -0.7239 -0.2159)
			(end 0.7239 -0.2159)
			(stroke
				(width 0.1)
				(type default)
			)
			(layer "B.Fab")
		)
		(fp_line
			(start 0.7239 1.9939)
			(end -0.7239 1.9939)
			(stroke
				(width 0.1)
				(type default)
			)
			(layer "B.Fab")
		)
		(fp_line
			(start -0.7239 1.9939)
			(end -0.7239 -0.2159)
			(stroke
				(width 0.1)
				(type default)
			)
			(layer "B.Fab")
		)
		(pad "1" smd rect
			(at 0 0 270)
			(size 1.27 1.016)
			(layers "B.Cu" "B.Mask" "B.Paste")
			(net "VR_FET_SW_P12V_STBY_PVDDQ_GHJ")
		)
		(pad "2" smd rect
			(at 0 1.778 270)
			(size 1.27 1.016)
			(layers "B.Cu" "B.Mask" "B.Paste")
			(net "GND")
		)
		(zone
			(layer "B.Cu")
			(hatch none 0.5)
			(connect_pads
				(clearance 0)
			)
			(min_thickness 0.25)
			(keepout
				(tracks not_allowed)
				(vias allowed)
				(pads allowed)
				(copperpour not_allowed)
				(footprints allowed)
			)
			(placement
				(enabled no)
				(sheetname "")
			)
			(fill
				(thermal_gap 0.5)
				(thermal_bridge_width 0.5)
				(island_removal_mode 0)
			)
			(polygon
				(pts
					(xy 4.3307 -8.929116) (xy 5.0927 -8.929116) (xy 5.0927 -10.199116) (xy 4.3307 -10.199116)
				)
			)
		)
	)
	(footprint ""
		(layer "B.Cu")
		(at 338.934806 -60.368434)
		(property "Reference" "R2U18"
			(at 0 0 0)
			(layer "B.SilkS")
			(hide yes)
			(effects
				(font
					(size 1.27 1.27)
				)
				(justify mirror)
			)
		)
		(property "Value" ""
			(at 0 0 0)
			(layer "B.Fab")
			(effects
				(font
					(size 1.27 1.27)
				)
				(justify mirror)
			)
		)
		(duplicate_pad_numbers_are_jumpers no)
		(fp_poly
			(pts
				(xy 0.2794 -0.1016) (xy -0.2794 -0.1016) (xy -0.2794 0.9906) (xy 0.2794 0.9906)
			)
			(stroke
				(width 0)
				(type default)
			)
			(fill no)
			(layer "B.CrtYd")
		)
		(fp_line
			(start -0.2794 -0.1016)
			(end 0.2794 -0.1016)
			(stroke
				(width 0.1)
				(type default)
			)
			(layer "B.Fab")
		)
		(fp_line
			(start -0.2794 0.9906)
			(end -0.2794 -0.1016)
			(stroke
				(width 0.1)
				(type default)
			)
			(layer "B.Fab")
		)
		(fp_line
			(start 0.2794 -0.1016)
			(end 0.2794 0.9906)
			(stroke
				(width 0.1)
				(type default)
			)
			(layer "B.Fab")
		)
		(fp_line
			(start 0.2794 0.9906)
			(end -0.2794 0.9906)
			(stroke
				(width 0.1)
				(type default)
			)
			(layer "B.Fab")
		)
		(pad "1" smd rect
			(at 0 0 180)
			(size 0.508 0.508)
			(layers "B.Cu" "B.Mask" "B.Paste")
			(net "P3E_CPU0_PE1_SS_RXP<2>")
		)
		(pad "2" smd rect
			(at 0 0.889 180)
			(size 0.508 0.508)
			(layers "B.Cu" "B.Mask" "B.Paste")
			(net "P3E_CPU0_PE1_SS_R_RXP<2>")
		)
		(zone
			(layer "B.Cu")
			(hatch none 0.5)
			(connect_pads
				(clearance 0)
			)
			(min_thickness 0.25)
			(keepout
				(tracks allowed)
				(vias not_allowed)
				(pads allowed)
				(copperpour not_allowed)
				(footprints allowed)
			)
			(placement
				(enabled no)
				(sheetname "")
			)
			(fill
				(thermal_gap 0.5)
				(thermal_bridge_width 0.5)
				(island_removal_mode 0)
			)
			(polygon
				(pts
					(xy 339.188806 -60.114434) (xy 338.680806 -60.114434) (xy 338.680806 -59.733434) (xy 339.188806 -59.733434)
				)
			)
		)
		(zone
			(layer "B.Cu")
			(hatch none 0.5)
			(connect_pads
				(clearance 0)
			)
			(min_thickness 0.25)
			(keepout
				(tracks not_allowed)
				(vias allowed)
				(pads allowed)
				(copperpour not_allowed)
				(footprints allowed)
			)
			(placement
				(enabled no)
				(sheetname "")
			)
			(fill
				(thermal_gap 0.5)
				(thermal_bridge_width 0.5)
				(island_removal_mode 0)
			)
			(polygon
				(pts
					(xy 339.188806 -59.733434) (xy 338.680806 -59.733434) (xy 338.680806 -60.114434) (xy 339.188806 -60.114434)
				)
			)
		)
	)
)
